(kicad_pcb
	(version 20241229)
	(generator "pcbnew")
	(generator_version "9.0")
	(general
		(thickness 1.552)
		(legacy_teardrops no)
	)
	(paper "A4")
	(title_block
		(date "2023-07-25")
		(rev "1.1.4")
		(comment 9 "footprints 327-331 of 379")
	)
	(layers
		(0 "F.Cu" signal)
		(4 "In1.Cu" signal)
		(6 "In2.Cu" signal)
		(8 "In3.Cu" signal)
		(10 "In4.Cu" signal)
		(12 "In5.Cu" signal)
		(14 "In6.Cu" signal)
		(2 "B.Cu" signal)
		(9 "F.Adhes" user "F.Adhesive")
		(11 "B.Adhes" user "B.Adhesive")
		(13 "F.Paste" user)
		(15 "B.Paste" user)
		(5 "F.SilkS" user "F.Silkscreen")
		(7 "B.SilkS" user "B.Silkscreen")
		(1 "F.Mask" user)
		(3 "B.Mask" user)
		(17 "Dwgs.User" user "User.Drawings")
		(19 "Cmts.User" user "User.Comments")
		(21 "Eco1.User" user "User.Eco1")
		(23 "Eco2.User" user "User.Eco2")
		(25 "Edge.Cuts" user)
		(27 "Margin" user)
		(31 "F.CrtYd" user "F.Courtyard")
		(29 "B.CrtYd" user "B.Courtyard")
		(35 "F.Fab" user)
		(33 "B.Fab" user)
	)
	(footprint "antmicro-footprints:C_0402_1005Metric"
		(layer "B.Cu")
		(at 97.1 84 90)
		(descr "Capacitor SMD 0402")
		(tags "capacitor SMD 0402")
		(property "Reference" "C67"
			(at -0.94 -0.67 90)
			(layer "B.SilkS")
			(effects
				(font
					(size 0.65 0.65)
					(thickness 0.15)
				)
				(justify right bottom mirror)
			)
		)
		(property "Value" "C_100n_0402"
			(at 0 -1.4 90)
			(layer "B.Fab")
			(hide yes)
			(effects
				(font
					(size 0.7 0.7)
					(thickness 0.15)
				)
				(justify right bottom mirror)
			)
		)
		(property "Datasheet" "https://www.murata.com/products/productdetail?partno=GRM155R61H104KE14%23"
			(at 0 0 90)
			(layer "F.Fab")
			(hide yes)
			(effects
				(font
					(size 1.27 1.27)
					(thickness 0.15)
				)
			)
		)
		(property "Description" "SMD Multilayer Ceramic Capacitor, 0.1 µF, 50 V, 0402 [1005 Metric], ± 10%, X5R, GRM Series"
			(at 0 0 90)
			(layer "F.Fab")
			(hide yes)
			(effects
				(font
					(size 1.27 1.27)
					(thickness 0.15)
				)
			)
		)
		(property "Author" "Antmicro"
			(at 181.1 -13.1 0)
			(layer "B.Fab")
			(hide yes)
			(effects
				(font
					(size 1 1)
					(thickness 0.15)
				)
				(justify mirror)
			)
		)
		(property "Dielectric" "X5R"
			(at 181.1 -13.1 0)
			(layer "B.Fab")
			(hide yes)
			(effects
				(font
					(size 1 1)
					(thickness 0.15)
				)
				(justify mirror)
			)
		)
		(property "License" "Apache-2.0"
			(at 181.1 -13.1 0)
			(layer "B.Fab")
			(hide yes)
			(effects
				(font
					(size 1 1)
					(thickness 0.15)
				)
				(justify mirror)
			)
		)
		(property "MPN" "GRM155R61H104KE14D"
			(at 181.1 -13.1 0)
			(layer "B.Fab")
			(hide yes)
			(effects
				(font
					(size 1 1)
					(thickness 0.15)
				)
				(justify mirror)
			)
		)
		(property "Manufacturer" "Murata"
			(at 181.1 -13.1 0)
			(layer "B.Fab")
			(hide yes)
			(effects
				(font
					(size 1 1)
					(thickness 0.15)
				)
				(justify mirror)
			)
		)
		(property "Val" "100n"
			(at 181.1 -13.1 0)
			(layer "B.Fab")
			(hide yes)
			(effects
				(font
					(size 1 1)
					(thickness 0.15)
				)
				(justify mirror)
			)
		)
		(property "Voltage" "50V"
			(at 181.1 -13.1 0)
			(layer "B.Fab")
			(hide yes)
			(effects
				(font
					(size 1 1)
					(thickness 0.15)
				)
				(justify mirror)
			)
		)
		(sheetname "/SDI/")
		(sheetfile "sdi.kicad_sch")
		(attr smd)
		(fp_rect
			(start -0.925 0.47)
			(end 0.925 -0.47)
			(stroke
				(width 0.05)
				(type default)
			)
			(fill no)
			(layer "B.CrtYd")
		)
		(fp_line
			(start 0.504 -0.248)
			(end -0.494 -0.248)
			(stroke
				(width 0.15)
				(type solid)
			)
			(layer "B.Fab")
		)
		(fp_line
			(start -0.494 -0.248)
			(end -0.494 0.25)
			(stroke
				(width 0.15)
				(type solid)
			)
			(layer "B.Fab")
		)
		(fp_line
			(start 0.504 0.25)
			(end 0.504 -0.248)
			(stroke
				(width 0.15)
				(type solid)
			)
			(layer "B.Fab")
		)
		(fp_line
			(start -0.494 0.25)
			(end 0.504 0.25)
			(stroke
				(width 0.15)
				(type solid)
			)
			(layer "B.Fab")
		)
		(fp_text user "${REFERENCE}"
			(at -0.939 -4.599 270)
			(layer "B.Fab")
			(effects
				(font
					(size 0.7 0.7)
					(thickness 0.15)
				)
				(justify left bottom mirror)
			)
		)
		(fp_text user "License: Apache-2.0"
			(at -0.939 -5.799 270)
			(layer "B.Fab")
			(effects
				(font
					(size 0.7 0.7)
					(thickness 0.15)
				)
				(justify left bottom mirror)
			)
		)
		(fp_text user "Author: Antmicro"
			(at -0.939 -3.399 270)
			(layer "B.Fab")
			(effects
				(font
					(size 0.7 0.7)
					(thickness 0.15)
				)
				(justify left bottom mirror)
			)
		)
		(pad "1" smd roundrect
			(at -0.48 0 90)
			(size 0.59 0.64)
			(layers "B.Cu" "B.Mask" "B.Paste")
			(roundrect_rratio 0.25)
			(net 1 "GND")
			(pintype "passive")
		)
		(pad "2" smd roundrect
			(at 0.48 0 90)
			(size 0.59 0.64)
			(layers "B.Cu" "B.Mask" "B.Paste")
			(roundrect_rratio 0.25)
			(net 2 "+3V3")
			(pintype "passive")
		)
	)
	(footprint "antmicro-footprints:R_0402_1005Metric"
		(layer "B.Cu")
		(at 104.19 96.8 -90)
		(descr "Resistor SMD 0402")
		(tags "resistor SMD 0402")
		(property "Reference" "R71"
			(at 0.94 -0.34 90)
			(layer "B.SilkS")
			(effects
				(font
					(size 0.65 0.65)
					(thickness 0.15)
				)
				(justify left bottom mirror)
			)
		)
		(property "Value" "R_0R_0402"
			(at 0 -1.4 90)
			(layer "B.Fab")
			(hide yes)
			(effects
				(font
					(size 0.7 0.7)
					(thickness 0.15)
				)
				(justify left bottom mirror)
			)
		)
		(property "Datasheet" "https://industrial.panasonic.com/cdbs/www-data/pdf/RDA0000/AOA0000C301.pdf"
			(at 0 0 270)
			(layer "F.Fab")
			(hide yes)
			(effects
				(font
					(size 1.27 1.27)
					(thickness 0.15)
				)
			)
		)
		(property "Description" "SMD Chip Resistor, Jumper, 0 ohm, 100 mW, 0402 [1005 Metric], Thick Film, General Purpose"
			(at 0 0 270)
			(layer "F.Fab")
			(hide yes)
			(effects
				(font
					(size 1.27 1.27)
					(thickness 0.15)
				)
			)
		)
		(property "Author" "Antmicro"
			(at 7.39 200.99 0)
			(layer "B.Fab")
			(hide yes)
			(effects
				(font
					(size 1 1)
					(thickness 0.15)
				)
				(justify mirror)
			)
		)
		(property "Current" "1A"
			(at 7.39 200.99 0)
			(layer "B.Fab")
			(hide yes)
			(effects
				(font
					(size 1 1)
					(thickness 0.15)
				)
				(justify mirror)
			)
		)
		(property "License" "Apache-2.0"
			(at 7.39 200.99 0)
			(layer "B.Fab")
			(hide yes)
			(effects
				(font
					(size 1 1)
					(thickness 0.15)
				)
				(justify mirror)
			)
		)
		(property "MPN" "ERJ2GE0R00X"
			(at 7.39 200.99 0)
			(layer "B.Fab")
			(hide yes)
			(effects
				(font
					(size 1 1)
					(thickness 0.15)
				)
				(justify mirror)
			)
		)
		(property "Manufacturer" "Panasonic"
			(at 7.39 200.99 0)
			(layer "B.Fab")
			(hide yes)
			(effects
				(font
					(size 1 1)
					(thickness 0.15)
				)
				(justify mirror)
			)
		)
		(property "Tolerance" "~"
			(at 7.39 200.99 0)
			(layer "B.Fab")
			(hide yes)
			(effects
				(font
					(size 1 1)
					(thickness 0.15)
				)
				(justify mirror)
			)
		)
		(property "Val" "0R"
			(at 7.39 200.99 0)
			(layer "B.Fab")
			(hide yes)
			(effects
				(font
					(size 1 1)
					(thickness 0.15)
				)
				(justify mirror)
			)
		)
		(sheetname "/FPGA/")
		(sheetfile "fpga.kicad_sch")
		(attr smd)
		(fp_rect
			(start -0.925 0.47)
			(end 0.925 -0.47)
			(stroke
				(width 0.05)
				(type default)
			)
			(fill no)
			(layer "B.CrtYd")
		)
		(fp_rect
			(start -0.5 0.25)
			(end 0.5 -0.25)
			(stroke
				(width 0.15)
				(type solid)
			)
			(fill no)
			(layer "B.Fab")
		)
		(fp_text user "${REFERENCE}"
			(at -0.95 -3.168 90)
			(layer "B.Fab")
			(effects
				(font
					(size 0.7 0.7)
					(thickness 0.15)
				)
				(justify left bottom mirror)
			)
		)
		(fp_text user "License: Apache-2.0"
			(at -0.95 -5.169 90)
			(layer "B.Fab")
			(effects
				(font
					(size 0.7 0.7)
					(thickness 0.15)
				)
				(justify left bottom mirror)
			)
		)
		(fp_text user "Author: Antmicro"
			(at -0.95 -4.169 90)
			(layer "B.Fab")
			(effects
				(font
					(size 0.7 0.7)
					(thickness 0.15)
				)
				(justify left bottom mirror)
			)
		)
		(pad "1" smd roundrect
			(at -0.48 0 270)
			(size 0.59 0.64)
			(layers "B.Cu" "B.Mask" "B.Paste")
			(roundrect_rratio 0.25)
			(net 301 "Net-(U18-SO{slash}IO1)")
			(pintype "passive")
		)
		(pad "2" smd roundrect
			(at 0.48 0 270)
			(size 0.59 0.64)
			(layers "B.Cu" "B.Mask" "B.Paste")
			(roundrect_rratio 0.25)
			(net 38 "/FPGA/SPI_DQ1_MISO")
			(pintype "passive")
		)
	)
	(footprint "antmicro-footprints:TP_SMD_0.75mm"
		(layer "B.Cu")
		(at 99.94 88.2 90)
		(property "Reference" "TP37"
			(at 0.76 0.39 90)
			(layer "B.SilkS")
			(effects
				(font
					(size 0.65 0.65)
					(thickness 0.15)
				)
				(justify right bottom mirror)
			)
		)
		(property "Value" "TP_0.75mm_SMD"
			(at 0 -1.2 90)
			(layer "B.Fab")
			(hide yes)
			(effects
				(font
					(size 0.7 0.7)
					(thickness 0.15)
				)
				(justify right bottom mirror)
			)
		)
		(property "Description" "SMT test point"
			(at 0 0 90)
			(layer "F.Fab")
			(hide yes)
			(effects
				(font
					(size 1.27 1.27)
					(thickness 0.15)
				)
			)
		)
		(property "Author" "Antmicro"
			(at 188.14 -11.74 0)
			(layer "B.Fab")
			(hide yes)
			(effects
				(font
					(size 1 1)
					(thickness 0.15)
				)
				(justify mirror)
			)
		)
		(property "License" "Apache-2.0"
			(at 188.14 -11.74 0)
			(layer "B.Fab")
			(hide yes)
			(effects
				(font
					(size 1 1)
					(thickness 0.15)
				)
				(justify mirror)
			)
		)
		(property "MPN" ""
			(at 188.14 -11.74 0)
			(layer "B.Fab")
			(hide yes)
			(effects
				(font
					(size 1 1)
					(thickness 0.15)
				)
				(justify mirror)
			)
		)
		(property "Manufacturer" ""
			(at 188.14 -11.74 0)
			(layer "B.Fab")
			(hide yes)
			(effects
				(font
					(size 1 1)
					(thickness 0.15)
				)
				(justify mirror)
			)
		)
		(sheetname "/SDI/")
		(sheetfile "sdi.kicad_sch")
		(attr exclude_from_pos_files)
		(fp_circle
			(center 0 0)
			(end 0.475 0)
			(stroke
				(width 0.05)
				(type default)
			)
			(fill no)
			(layer "B.CrtYd")
		)
		(fp_text user "${REFERENCE}"
			(at -0.4 -2.7 270)
			(layer "B.Fab")
			(effects
				(font
					(size 0.7 0.7)
					(thickness 0.15)
				)
				(justify left bottom mirror)
			)
		)
		(fp_text user "Author: Antmicro"
			(at -0.4 -3.901 270)
			(layer "B.Fab")
			(effects
				(font
					(size 0.7 0.7)
					(thickness 0.15)
				)
				(justify left bottom mirror)
			)
		)
		(fp_text user "License: Apache-2.0"
			(at -0.4 -5.101 270)
			(layer "B.Fab")
			(effects
				(font
					(size 0.7 0.7)
					(thickness 0.15)
				)
				(justify left bottom mirror)
			)
		)
		(pad "1" smd circle
			(at 0 0 90)
			(size 0.75 0.75)
			(layers "B.Cu" "B.Mask")
			(net 179 "/SDI/SCLK_TCK")
			(pinfunction "1")
			(pintype "passive")
		)
	)
	(footprint "antmicro-footprints:C_0402_1005Metric"
		(layer "B.Cu")
		(at 120.32 59.7 -135)
		(descr "Capacitor SMD 0402")
		(tags "capacitor SMD 0402")
		(property "Reference" "C42"
			(at -0.827315 0.671751 45)
			(layer "B.SilkS")
			(effects
				(font
					(size 0.65 0.65)
					(thickness 0.15)
				)
				(justify left bottom mirror)
			)
		)
		(property "Value" "C_100n_0402"
			(at 0 -1.399999 45)
			(layer "B.Fab")
			(hide yes)
			(effects
				(font
					(size 0.7 0.7)
					(thickness 0.15)
				)
				(justify left bottom mirror)
			)
		)
		(property "Datasheet" "https://www.murata.com/products/productdetail?partno=GRM155R61H104KE14%23"
			(at 0 0 225)
			(layer "F.Fab")
			(hide yes)
			(effects
				(font
					(size 1.27 1.27)
					(thickness 0.15)
				)
			)
		)
		(property "Description" "SMD Multilayer Ceramic Capacitor, 0.1 µF, 50 V, 0402 [1005 Metric], ± 10%, X5R, GRM Series"
			(at 0 0 225)
			(layer "F.Fab")
			(hide yes)
			(effects
				(font
					(size 1.27 1.27)
					(thickness 0.15)
				)
			)
		)
		(property "Author" "Antmicro"
			(at 163.184813 186.993363 0)
			(layer "B.Fab")
			(hide yes)
			(effects
				(font
					(size 1 1)
					(thickness 0.15)
				)
				(justify mirror)
			)
		)
		(property "Dielectric" "X5R"
			(at 163.184813 186.993363 0)
			(layer "B.Fab")
			(hide yes)
			(effects
				(font
					(size 1 1)
					(thickness 0.15)
				)
				(justify mirror)
			)
		)
		(property "License" "Apache-2.0"
			(at 163.184813 186.993363 0)
			(layer "B.Fab")
			(hide yes)
			(effects
				(font
					(size 1 1)
					(thickness 0.15)
				)
				(justify mirror)
			)
		)
		(property "MPN" "GRM155R61H104KE14D"
			(at 163.184813 186.993363 0)
			(layer "B.Fab")
			(hide yes)
			(effects
				(font
					(size 1 1)
					(thickness 0.15)
				)
				(justify mirror)
			)
		)
		(property "Manufacturer" "Murata"
			(at 163.184813 186.993363 0)
			(layer "B.Fab")
			(hide yes)
			(effects
				(font
					(size 1 1)
					(thickness 0.15)
				)
				(justify mirror)
			)
		)
		(property "Val" "100n"
			(at 163.184813 186.993363 0)
			(layer "B.Fab")
			(hide yes)
			(effects
				(font
					(size 1 1)
					(thickness 0.15)
				)
				(justify mirror)
			)
		)
		(property "Voltage" "50V"
			(at 163.184813 186.993363 0)
			(layer "B.Fab")
			(hide yes)
			(effects
				(font
					(size 1 1)
					(thickness 0.15)
				)
				(justify mirror)
			)
		)
		(sheetname "/DDR3/")
		(sheetfile "ddr3.kicad_sch")
		(attr smd)
		(fp_poly
			(pts
				(xy -0.925 0.47) (xy 0.925 0.47) (xy 0.925 -0.47) (xy -0.925 -0.47)
			)
			(stroke
				(width 0.05)
				(type default)
			)
			(fill no)
			(layer "B.CrtYd")
		)
		(fp_line
			(start 0.504 0.25)
			(end 0.504 -0.248)
			(stroke
				(width 0.15)
				(type solid)
			)
			(layer "B.Fab")
		)
		(fp_line
			(start 0.504 -0.248)
			(end -0.494 -0.248)
			(stroke
				(width 0.15)
				(type solid)
			)
			(layer "B.Fab")
		)
		(fp_line
			(start -0.494 0.25)
			(end 0.504 0.25)
			(stroke
				(width 0.15)
				(type solid)
			)
			(layer "B.Fab")
		)
		(fp_line
			(start -0.494 -0.248)
			(end -0.494 0.25)
			(stroke
				(width 0.15)
				(type solid)
			)
			(layer "B.Fab")
		)
		(fp_text user "Author: Antmicro"
			(at -0.939 -3.399 45)
			(layer "B.Fab")
			(effects
				(font
					(size 0.7 0.7)
					(thickness 0.15)
				)
				(justify left bottom mirror)
			)
		)
		(fp_text user "${REFERENCE}"
			(at -0.939 -4.599 45)
			(layer "B.Fab")
			(effects
				(font
					(size 0.7 0.7)
					(thickness 0.15)
				)
				(justify left bottom mirror)
			)
		)
		(fp_text user "License: Apache-2.0"
			(at -0.939 -5.799 45)
			(layer "B.Fab")
			(effects
				(font
					(size 0.7 0.7)
					(thickness 0.15)
				)
				(justify left bottom mirror)
			)
		)
		(pad "1" smd roundrect
			(at -0.48 0 225)
			(size 0.59 0.64)
			(layers "B.Cu" "B.Mask" "B.Paste")
			(roundrect_rratio 0.25)
			(net 1 "GND")
			(pintype "passive")
		)
		(pad "2" smd roundrect
			(at 0.48 0 225)
			(size 0.59 0.64)
			(layers "B.Cu" "B.Mask" "B.Paste")
			(roundrect_rratio 0.25)
			(net 248 "+1V5")
			(pintype "passive")
		)
	)
	(footprint "antmicro-footprints:C_0402_1005Metric"
		(layer "B.Cu")
		(at 93.65 75.79 -90)
		(descr "Capacitor SMD 0402")
		(tags "capacitor SMD 0402")
		(property "Reference" "C63"
			(at -0.95 0.7 90)
			(layer "B.SilkS")
			(effects
				(font
					(size 0.65 0.65)
					(thickness 0.15)
				)
				(justify left bottom mirror)
			)
		)
		(property "Value" "C_100n_0402"
			(at 0 -1.4 90)
			(layer "B.Fab")
			(hide yes)
			(effects
				(font
					(size 0.7 0.7)
					(thickness 0.15)
				)
				(justify left bottom mirror)
			)
		)
		(property "Datasheet" "https://www.murata.com/products/productdetail?partno=GRM155R61H104KE14%23"
			(at 0 0 270)
			(layer "F.Fab")
			(hide yes)
			(effects
				(font
					(size 1.27 1.27)
					(thickness 0.15)
				)
			)
		)
		(property "Description" "SMD Multilayer Ceramic Capacitor, 0.1 µF, 50 V, 0402 [1005 Metric], ± 10%, X5R, GRM Series"
			(at 0 0 270)
			(layer "F.Fab")
			(hide yes)
			(effects
				(font
					(size 1.27 1.27)
					(thickness 0.15)
				)
			)
		)
		(property "Author" "Antmicro"
			(at 17.86 169.44 0)
			(layer "B.Fab")
			(hide yes)
			(effects
				(font
					(size 1 1)
					(thickness 0.15)
				)
				(justify mirror)
			)
		)
		(property "Dielectric" "X5R"
			(at 17.86 169.44 0)
			(layer "B.Fab")
			(hide yes)
			(effects
				(font
					(size 1 1)
					(thickness 0.15)
				)
				(justify mirror)
			)
		)
		(property "License" "Apache-2.0"
			(at 17.86 169.44 0)
			(layer "B.Fab")
			(hide yes)
			(effects
				(font
					(size 1 1)
					(thickness 0.15)
				)
				(justify mirror)
			)
		)
		(property "MPN" "GRM155R61H104KE14D"
			(at 17.86 169.44 0)
			(layer "B.Fab")
			(hide yes)
			(effects
				(font
					(size 1 1)
					(thickness 0.15)
				)
				(justify mirror)
			)
		)
		(property "Manufacturer" "Murata"
			(at 17.86 169.44 0)
			(layer "B.Fab")
			(hide yes)
			(effects
				(font
					(size 1 1)
					(thickness 0.15)
				)
				(justify mirror)
			)
		)
		(property "Val" "100n"
			(at 17.86 169.44 0)
			(layer "B.Fab")
			(hide yes)
			(effects
				(font
					(size 1 1)
					(thickness 0.15)
				)
				(justify mirror)
			)
		)
		(property "Voltage" "50V"
			(at 17.86 169.44 0)
			(layer "B.Fab")
			(hide yes)
			(effects
				(font
					(size 1 1)
					(thickness 0.15)
				)
				(justify mirror)
			)
		)
		(sheetname "/SDI/")
		(sheetfile "sdi.kicad_sch")
		(attr smd)
		(fp_rect
			(start -0.925 0.47)
			(end 0.925 -0.47)
			(stroke
				(width 0.05)
				(type default)
			)
			(fill no)
			(layer "B.CrtYd")
		)
		(fp_line
			(start -0.494 0.25)
			(end 0.504 0.25)
			(stroke
				(width 0.15)
				(type solid)
			)
			(layer "B.Fab")
		)
		(fp_line
			(start 0.504 0.25)
			(end 0.504 -0.248)
			(stroke
				(width 0.15)
				(type solid)
			)
			(layer "B.Fab")
		)
		(fp_line
			(start -0.494 -0.248)
			(end -0.494 0.25)
			(stroke
				(width 0.15)
				(type solid)
			)
			(layer "B.Fab")
		)
		(fp_line
			(start 0.504 -0.248)
			(end -0.494 -0.248)
			(stroke
				(width 0.15)
				(type solid)
			)
			(layer "B.Fab")
		)
		(fp_text user "Author: Antmicro"
			(at -0.939 -3.399 90)
			(layer "B.Fab")
			(effects
				(font
					(size 0.7 0.7)
					(thickness 0.15)
				)
				(justify left bottom mirror)
			)
		)
		(fp_text user "License: Apache-2.0"
			(at -0.939 -5.799 90)
			(layer "B.Fab")
			(effects
				(font
					(size 0.7 0.7)
					(thickness 0.15)
				)
				(justify left bottom mirror)
			)
		)
		(fp_text user "${REFERENCE}"
			(at -0.939 -4.599 90)
			(layer "B.Fab")
			(effects
				(font
					(size 0.7 0.7)
					(thickness 0.15)
				)
				(justify left bottom mirror)
			)
		)
		(pad "1" smd roundrect
			(at -0.48 0 270)
			(size 0.59 0.64)
			(layers "B.Cu" "B.Mask" "B.Paste")
			(roundrect_rratio 0.25)
			(net 1 "GND")
			(pintype "passive")
		)
		(pad "2" smd roundrect
			(at 0.48 0 270)
			(size 0.59 0.64)
			(layers "B.Cu" "B.Mask" "B.Paste")
			(roundrect_rratio 0.25)
			(net 3 "+1V2")
			(pintype "passive")
		)
	)
)
